(kicad_pcb
	(version 20260206)
	(generator "pcbnew")
	(generator_version "10.0")
	(general
		(thickness 1.6)
		(legacy_teardrops no)
	)
	(paper "A4")
	(title_block
		(title "03242023_DA0F0TMBIJ0_F0T_Motherboard_J_brd_V01_OCP.brd")
		(comment 1 "Grand Teton / footprints 2119-2123 of 6105")
	)
	(layers
		(0 "F.Cu" signal "TOP")
		(4 "In1.Cu" signal "GND")
		(6 "In2.Cu" signal "IN1")
		(8 "In3.Cu" signal "GND1")
		(10 "In4.Cu" signal "IN2")
		(12 "In5.Cu" signal "GND2")
		(14 "In6.Cu" signal "IN3")
		(16 "In7.Cu" signal "GND3")
		(18 "In8.Cu" signal "VCC")
		(20 "In9.Cu" signal "VCC1")
		(22 "In10.Cu" signal "GND4")
		(24 "In11.Cu" signal "IN4")
		(26 "In12.Cu" signal "GND5")
		(28 "In13.Cu" signal "IN5")
		(30 "In14.Cu" signal "GND6")
		(32 "In15.Cu" signal "IN6")
		(34 "In16.Cu" signal "GND7")
		(2 "B.Cu" signal "BOTTOM")
		(9 "F.Adhes" user "F.Adhesive")
		(11 "B.Adhes" user "B.Adhesive")
		(13 "F.Paste" user "Package Geometry/Pastemask Top")
		(15 "B.Paste" user "Package Geometry/Pastemask Bottom")
		(5 "F.SilkS" user "Ref Des/Silkscreen Top")
		(7 "B.SilkS" user "Ref Des/Silkscreen Bottom")
		(1 "F.Mask" user "Board Geometry/Soldermask Top")
		(3 "B.Mask" user "Board Geometry/Soldermask Bottom")
		(17 "Dwgs.User" user "User.Drawings")
		(19 "Cmts.User" user "User.Comments")
		(21 "Eco1.User" user "User.Eco1")
		(23 "Eco2.User" user "User.Eco2")
		(25 "Edge.Cuts" user "Board Geometry/Outline")
		(27 "Margin" user)
		(31 "F.CrtYd" user "Package Geometry/Place Bound Top")
		(29 "B.CrtYd" user "Package Geometry/Place Bound Bottom")
		(35 "F.Fab" user "Ref Des/Assembly Top")
		(33 "B.Fab" user "Ref Des/Assembly Bottom")
	)
	(footprint ""
		(layer "F.Cu")
		(at 501.233948 2.33426 -90)
		(property "Reference" "X21"
			(at -1.33604 3.115818 90)
			(unlocked yes)
			(layer "F.SilkS")
			(effects
				(font
					(size 0.7874 0.5842)
					(thickness 0.1524)
				)
				(justify left)
			)
		)
		(property "Value" ""
			(at 0 0 270)
			(layer "F.Fab")
			(effects
				(font
					(size 1.27 1.27)
				)
			)
		)
		(property "Device Type" "TP_TDR_4P_FTS_MPKT4_H025P0200_I"
			(at 1.30175 1.27 0)
			(unlocked yes)
			(layer "F.Fab")
			(hide yes)
			(effects
				(font
					(size 0.635 0.4064)
					(thickness 0.1524)
				)
			)
		)
		(property "User Part Number" "TP15"
			(at 1.30175 1.27 0)
			(unlocked yes)
			(layer "Cmts.User")
			(hide yes)
			(effects
				(font
					(size 0.635 0.4064)
					(thickness 0.1524)
				)
			)
		)
		(duplicate_pad_numbers_are_jumpers no)
		(fp_line
			(start 0 3.81)
			(end 2.54 3.81)
			(stroke
				(width 0.1524)
				(type default)
			)
			(layer "F.SilkS")
		)
		(fp_line
			(start 2.54 3.81)
			(end 2.54 3.6703)
			(stroke
				(width 0.1524)
				(type default)
			)
			(layer "F.SilkS")
		)
		(fp_line
			(start 0 3.175)
			(end 0 3.81)
			(stroke
				(width 0.1524)
				(type default)
			)
			(layer "F.SilkS")
		)
		(fp_line
			(start 2.54 1.4097)
			(end 2.54 1.1303)
			(stroke
				(width 0.1524)
				(type default)
			)
			(layer "F.SilkS")
		)
		(fp_line
			(start 0 0.635)
			(end 0 1.905)
			(stroke
				(width 0.1524)
				(type default)
			)
			(layer "F.SilkS")
		)
		(fp_line
			(start 2.54 -1.1303)
			(end 2.54 -1.27)
			(stroke
				(width 0.1524)
				(type default)
			)
			(layer "F.SilkS")
		)
		(fp_line
			(start 0 -1.27)
			(end 0 -0.635)
			(stroke
				(width 0.1524)
				(type default)
			)
			(layer "F.SilkS")
		)
		(fp_line
			(start 2.54 -1.27)
			(end 0 -1.27)
			(stroke
				(width 0.1524)
				(type default)
			)
			(layer "F.SilkS")
		)
		(fp_poly
			(pts
				(xy -1.3589 0.041148) (xy -2.8829 0.803148) (xy -2.8829 -0.720852)
			)
			(stroke
				(width 0)
				(type default)
			)
			(fill yes)
			(layer "F.SilkS")
		)
		(fp_line
			(start 0 3.81)
			(end 2.54 3.81)
			(stroke
				(width 0.1)
				(type default)
			)
			(layer "F.Fab")
		)
		(fp_line
			(start 2.54 3.81)
			(end 2.54 -1.27)
			(stroke
				(width 0.1)
				(type default)
			)
			(layer "F.Fab")
		)
		(fp_line
			(start 0 -1.27)
			(end 0 3.81)
			(stroke
				(width 0.1)
				(type default)
			)
			(layer "F.Fab")
		)
		(fp_line
			(start 2.54 -1.27)
			(end 0 -1.27)
			(stroke
				(width 0.1)
				(type default)
			)
			(layer "F.Fab")
		)
		(fp_poly
			(pts
				(xy -0.761746 0) (xy -2.285746 -0.762) (xy -2.285746 0.762)
			)
			(stroke
				(width 0)
				(type default)
			)
			(fill yes)
			(layer "F.Fab")
		)
		(pad "1" thru_hole circle
			(at 0 0 270)
			(size 1.0033 1.0033)
			(drill 0.249936)
			(layers "*.Cu" "*.Mask")
			(remove_unused_layers no)
			(net "TDR_DIFF_100_IN2_DN")
			(clearance 0.10795)
			(thermal_gap 0.10795)
			(padstack
				(mode front_inner_back)
				(layer "Inner"
					(shape circle)
					(size 0.8001 0.8001)
					(clearance 0.1524)
				)
				(layer "B.Cu"
					(shape circle)
					(size 1.0033 1.0033)
					(clearance 0.10795)
				)
			)
		)
		(pad "2" thru_hole circle
			(at 2.54 0 270)
			(size 1.9939 1.9939)
			(drill 0.249936)
			(layers "*.Cu" "*.Mask")
			(remove_unused_layers no)
			(net "T1_GND")
			(clearance 0.10795)
			(thermal_gap 0.10795)
			(padstack
				(mode front_inner_back)
				(layer "Inner"
					(shape circle)
					(size 0.8001 0.8001)
					(clearance 0.1524)
				)
				(layer "B.Cu"
					(shape circle)
					(size 1.9939 1.9939)
					(clearance 0.10795)
				)
			)
		)
		(pad "3" thru_hole circle
			(at 2.54 2.54 270)
			(size 1.9939 1.9939)
			(drill 0.249936)
			(layers "*.Cu" "*.Mask")
			(remove_unused_layers no)
			(net "T1_GND")
			(clearance 0.10795)
			(thermal_gap 0.10795)
			(padstack
				(mode front_inner_back)
				(layer "Inner"
					(shape circle)
					(size 0.8001 0.8001)
					(clearance 0.1524)
				)
				(layer "B.Cu"
					(shape circle)
					(size 1.9939 1.9939)
					(clearance 0.10795)
				)
			)
		)
		(pad "4" thru_hole circle
			(at 0 2.54 270)
			(size 1.0033 1.0033)
			(drill 0.249936)
			(layers "*.Cu" "*.Mask")
			(remove_unused_layers no)
			(net "TDR_DIFF_100_IN2_DP")
			(clearance 0.10795)
			(thermal_gap 0.10795)
			(padstack
				(mode front_inner_back)
				(layer "Inner"
					(shape circle)
					(size 0.8001 0.8001)
					(clearance 0.1524)
				)
				(layer "B.Cu"
					(shape circle)
					(size 1.0033 1.0033)
					(clearance 0.10795)
				)
			)
		)
	)
	(footprint ""
		(layer "F.Cu")
		(at 364.50143 -247.715024 90)
		(property "Reference" "C985"
			(at 0 0 90)
			(layer "F.SilkS")
			(hide yes)
			(effects
				(font
					(size 1.27 1.27)
				)
			)
		)
		(property "Value" ""
			(at 0 0 90)
			(layer "F.Fab")
			(effects
				(font
					(size 1.27 1.27)
				)
			)
		)
		(duplicate_pad_numbers_are_jumpers no)
		(fp_line
			(start 0.7874 -0.4064)
			(end 0.7874 0.4064)
			(stroke
				(width 0.1524)
				(type default)
			)
			(layer "F.SilkS")
		)
		(fp_line
			(start -0.7874 -0.4064)
			(end 0.7874 -0.4064)
			(stroke
				(width 0.1524)
				(type default)
			)
			(layer "F.SilkS")
		)
		(fp_line
			(start 0.7874 0.4064)
			(end -0.7874 0.4064)
			(stroke
				(width 0.1524)
				(type default)
			)
			(layer "F.SilkS")
		)
		(fp_line
			(start -0.7874 0.4064)
			(end -0.7874 -0.4064)
			(stroke
				(width 0.1524)
				(type default)
			)
			(layer "F.SilkS")
		)
		(fp_line
			(start -0.12065 -0.305054)
			(end -0.12065 -0.2794)
			(stroke
				(width 0.1)
				(type default)
			)
			(layer "F.Fab")
		)
		(fp_line
			(start -0.67945 -0.305054)
			(end -0.12065 -0.305054)
			(stroke
				(width 0.1)
				(type default)
			)
			(layer "F.Fab")
		)
		(fp_line
			(start 0.67945 -0.3048)
			(end 0.67945 0.3048)
			(stroke
				(width 0.1)
				(type default)
			)
			(layer "F.Fab")
		)
		(fp_line
			(start 0.12065 -0.3048)
			(end 0.67945 -0.3048)
			(stroke
				(width 0.1)
				(type default)
			)
			(layer "F.Fab")
		)
		(fp_line
			(start 0.12065 -0.2794)
			(end 0.12065 -0.3048)
			(stroke
				(width 0.1)
				(type default)
			)
			(layer "F.Fab")
		)
		(fp_line
			(start -0.12065 -0.2794)
			(end 0.12065 -0.2794)
			(stroke
				(width 0.1)
				(type default)
			)
			(layer "F.Fab")
		)
		(fp_line
			(start 0.120396 0.2794)
			(end -0.12065 0.2794)
			(stroke
				(width 0.1)
				(type default)
			)
			(layer "F.Fab")
		)
		(fp_line
			(start -0.12065 0.2794)
			(end -0.12065 0.3048)
			(stroke
				(width 0.1)
				(type default)
			)
			(layer "F.Fab")
		)
		(fp_line
			(start 0.67945 0.3048)
			(end 0.120396 0.3048)
			(stroke
				(width 0.1)
				(type default)
			)
			(layer "F.Fab")
		)
		(fp_line
			(start 0.120396 0.3048)
			(end 0.120396 0.2794)
			(stroke
				(width 0.1)
				(type default)
			)
			(layer "F.Fab")
		)
		(fp_line
			(start -0.12065 0.3048)
			(end -0.67945 0.3048)
			(stroke
				(width 0.1)
				(type default)
			)
			(layer "F.Fab")
		)
		(fp_line
			(start -0.67945 0.3048)
			(end -0.67945 -0.305054)
			(stroke
				(width 0.1)
				(type default)
			)
			(layer "F.Fab")
		)
		(pad "1" smd circle
			(at -0.40005 0 90)
			(size 0 0)
			(layers "F.Cu" "F.Mask" "F.Paste")
			(net "PVCCIN_CPU0")
		)
		(pad "2" smd circle
			(at 0.40005 0 90)
			(size 0 0)
			(layers "F.Cu" "F.Mask" "F.Paste")
			(net "GND")
		)
	)
	(footprint ""
		(layer "F.Cu")
		(at 228.760782 -126.383542 180)
		(property "Reference" "R564"
			(at 0 0 180)
			(layer "F.SilkS")
			(hide yes)
			(effects
				(font
					(size 1.27 1.27)
				)
			)
		)
		(property "Value" ""
			(at 0 0 180)
			(layer "F.Fab")
			(effects
				(font
					(size 1.27 1.27)
				)
			)
		)
		(duplicate_pad_numbers_are_jumpers no)
		(fp_line
			(start 0.7874 -0.4064)
			(end 0.7874 0.039878)
			(stroke
				(width 0.1524)
				(type default)
			)
			(layer "F.SilkS")
		)
		(fp_line
			(start 0.330962 0.4064)
			(end -0.433578 0.4064)
			(stroke
				(width 0.1524)
				(type default)
			)
			(layer "F.SilkS")
		)
		(fp_line
			(start -0.7874 0.029718)
			(end -0.7874 -0.4064)
			(stroke
				(width 0.1524)
				(type default)
			)
			(layer "F.SilkS")
		)
		(fp_line
			(start -0.7874 -0.4064)
			(end 0.7874 -0.4064)
			(stroke
				(width 0.1524)
				(type default)
			)
			(layer "F.SilkS")
		)
		(fp_line
			(start 0.67945 0.3048)
			(end 0.120396 0.3048)
			(stroke
				(width 0.1)
				(type default)
			)
			(layer "F.Fab")
		)
		(fp_line
			(start 0.67945 -0.3048)
			(end 0.67945 0.3048)
			(stroke
				(width 0.1)
				(type default)
			)
			(layer "F.Fab")
		)
		(fp_line
			(start 0.12065 -0.2794)
			(end 0.12065 -0.3048)
			(stroke
				(width 0.1)
				(type default)
			)
			(layer "F.Fab")
		)
		(fp_line
			(start 0.12065 -0.3048)
			(end 0.67945 -0.3048)
			(stroke
				(width 0.1)
				(type default)
			)
			(layer "F.Fab")
		)
		(fp_line
			(start 0.120396 0.3048)
			(end 0.120396 0.2794)
			(stroke
				(width 0.1)
				(type default)
			)
			(layer "F.Fab")
		)
		(fp_line
			(start 0.120396 0.2794)
			(end -0.12065 0.2794)
			(stroke
				(width 0.1)
				(type default)
			)
			(layer "F.Fab")
		)
		(fp_line
			(start -0.12065 0.3048)
			(end -0.67945 0.3048)
			(stroke
				(width 0.1)
				(type default)
			)
			(layer "F.Fab")
		)
		(fp_line
			(start -0.12065 0.2794)
			(end -0.12065 0.3048)
			(stroke
				(width 0.1)
				(type default)
			)
			(layer "F.Fab")
		)
		(fp_line
			(start -0.12065 -0.2794)
			(end 0.12065 -0.2794)
			(stroke
				(width 0.1)
				(type default)
			)
			(layer "F.Fab")
		)
		(fp_line
			(start -0.12065 -0.305054)
			(end -0.12065 -0.2794)
			(stroke
				(width 0.1)
				(type default)
			)
			(layer "F.Fab")
		)
		(fp_line
			(start -0.67945 0.3048)
			(end -0.67945 -0.305054)
			(stroke
				(width 0.1)
				(type default)
			)
			(layer "F.Fab")
		)
		(fp_line
			(start -0.67945 -0.305054)
			(end -0.12065 -0.305054)
			(stroke
				(width 0.1)
				(type default)
			)
			(layer "F.Fab")
		)
		(pad "1" smd circle
			(at -0.40005 0 180)
			(size 0 0)
			(layers "F.Cu" "F.Mask" "F.Paste")
			(net "CLK_100M_OCP_SFF_0_R_DN")
		)
		(pad "2" smd circle
			(at 0.40005 0 180)
			(size 0 0)
			(layers "F.Cu" "F.Mask" "F.Paste")
			(net "CLK_100M_OCP_SFF_0_DN")
		)
	)
	(footprint ""
		(layer "F.Cu")
		(at 364.50143 -251.375418 90)
		(property "Reference" "C1032"
			(at 0 0 90)
			(layer "F.SilkS")
			(hide yes)
			(effects
				(font
					(size 1.27 1.27)
				)
			)
		)
		(property "Value" ""
			(at 0 0 90)
			(layer "F.Fab")
			(effects
				(font
					(size 1.27 1.27)
				)
			)
		)
		(duplicate_pad_numbers_are_jumpers no)
		(fp_line
			(start 0.7874 -0.4064)
			(end 0.7874 0.4064)
			(stroke
				(width 0.1524)
				(type default)
			)
			(layer "F.SilkS")
		)
		(fp_line
			(start -0.7874 -0.4064)
			(end 0.7874 -0.4064)
			(stroke
				(width 0.1524)
				(type default)
			)
			(layer "F.SilkS")
		)
		(fp_line
			(start 0.7874 0.4064)
			(end -0.7874 0.4064)
			(stroke
				(width 0.1524)
				(type default)
			)
			(layer "F.SilkS")
		)
		(fp_line
			(start -0.7874 0.4064)
			(end -0.7874 -0.4064)
			(stroke
				(width 0.1524)
				(type default)
			)
			(layer "F.SilkS")
		)
		(fp_line
			(start -0.12065 -0.305054)
			(end -0.12065 -0.2794)
			(stroke
				(width 0.1)
				(type default)
			)
			(layer "F.Fab")
		)
		(fp_line
			(start -0.67945 -0.305054)
			(end -0.12065 -0.305054)
			(stroke
				(width 0.1)
				(type default)
			)
			(layer "F.Fab")
		)
		(fp_line
			(start 0.67945 -0.3048)
			(end 0.67945 0.3048)
			(stroke
				(width 0.1)
				(type default)
			)
			(layer "F.Fab")
		)
		(fp_line
			(start 0.12065 -0.3048)
			(end 0.67945 -0.3048)
			(stroke
				(width 0.1)
				(type default)
			)
			(layer "F.Fab")
		)
		(fp_line
			(start 0.12065 -0.2794)
			(end 0.12065 -0.3048)
			(stroke
				(width 0.1)
				(type default)
			)
			(layer "F.Fab")
		)
		(fp_line
			(start -0.12065 -0.2794)
			(end 0.12065 -0.2794)
			(stroke
				(width 0.1)
				(type default)
			)
			(layer "F.Fab")
		)
		(fp_line
			(start 0.120396 0.2794)
			(end -0.12065 0.2794)
			(stroke
				(width 0.1)
				(type default)
			)
			(layer "F.Fab")
		)
		(fp_line
			(start -0.12065 0.2794)
			(end -0.12065 0.3048)
			(stroke
				(width 0.1)
				(type default)
			)
			(layer "F.Fab")
		)
		(fp_line
			(start 0.67945 0.3048)
			(end 0.120396 0.3048)
			(stroke
				(width 0.1)
				(type default)
			)
			(layer "F.Fab")
		)
		(fp_line
			(start 0.120396 0.3048)
			(end 0.120396 0.2794)
			(stroke
				(width 0.1)
				(type default)
			)
			(layer "F.Fab")
		)
		(fp_line
			(start -0.12065 0.3048)
			(end -0.67945 0.3048)
			(stroke
				(width 0.1)
				(type default)
			)
			(layer "F.Fab")
		)
		(fp_line
			(start -0.67945 0.3048)
			(end -0.67945 -0.305054)
			(stroke
				(width 0.1)
				(type default)
			)
			(layer "F.Fab")
		)
		(pad "1" smd circle
			(at -0.40005 0 90)
			(size 0 0)
			(layers "F.Cu" "F.Mask" "F.Paste")
			(net "PVCCIN_CPU0")
		)
		(pad "2" smd circle
			(at 0.40005 0 90)
			(size 0 0)
			(layers "F.Cu" "F.Mask" "F.Paste")
			(net "GND")
		)
	)
	(footprint ""
		(layer "F.Cu")
		(at 174.90948 -424.398948)
		(property "Reference" "C1769"
			(at 0 0 0)
			(layer "F.SilkS")
			(hide yes)
			(effects
				(font
					(size 1.27 1.27)
				)
			)
		)
		(property "Value" ""
			(at 0 0 0)
			(layer "F.Fab")
			(effects
				(font
					(size 1.27 1.27)
				)
			)
		)
		(duplicate_pad_numbers_are_jumpers no)
		(fp_line
			(start -0.7874 -0.4064)
			(end 0.7874 -0.4064)
			(stroke
				(width 0.1524)
				(type default)
			)
			(layer "F.SilkS")
		)
		(fp_line
			(start -0.7874 0.4064)
			(end -0.7874 -0.4064)
			(stroke
				(width 0.1524)
				(type default)
			)
			(layer "F.SilkS")
		)
		(fp_line
			(start 0.7874 -0.4064)
			(end 0.7874 0.4064)
			(stroke
				(width 0.1524)
				(type default)
			)
			(layer "F.SilkS")
		)
		(fp_line
			(start 0.7874 0.4064)
			(end -0.7874 0.4064)
			(stroke
				(width 0.1524)
				(type default)
			)
			(layer "F.SilkS")
		)
		(fp_line
			(start -0.67945 -0.305054)
			(end -0.12065 -0.305054)
			(stroke
				(width 0.1)
				(type default)
			)
			(layer "F.Fab")
		)
		(fp_line
			(start -0.67945 0.3048)
			(end -0.67945 -0.305054)
			(stroke
				(width 0.1)
				(type default)
			)
			(layer "F.Fab")
		)
		(fp_line
			(start -0.12065 -0.305054)
			(end -0.12065 -0.2794)
			(stroke
				(width 0.1)
				(type default)
			)
			(layer "F.Fab")
		)
		(fp_line
			(start -0.12065 -0.2794)
			(end 0.12065 -0.2794)
			(stroke
				(width 0.1)
				(type default)
			)
			(layer "F.Fab")
		)
		(fp_line
			(start -0.12065 0.2794)
			(end -0.12065 0.3048)
			(stroke
				(width 0.1)
				(type default)
			)
			(layer "F.Fab")
		)
		(fp_line
			(start -0.12065 0.3048)
			(end -0.67945 0.3048)
			(stroke
				(width 0.1)
				(type default)
			)
			(layer "F.Fab")
		)
		(fp_line
			(start 0.120396 0.2794)
			(end -0.12065 0.2794)
			(stroke
				(width 0.1)
				(type default)
			)
			(layer "F.Fab")
		)
		(fp_line
			(start 0.120396 0.3048)
			(end 0.120396 0.2794)
			(stroke
				(width 0.1)
				(type default)
			)
			(layer "F.Fab")
		)
		(fp_line
			(start 0.12065 -0.3048)
			(end 0.67945 -0.3048)
			(stroke
				(width 0.1)
				(type default)
			)
			(layer "F.Fab")
		)
		(fp_line
			(start 0.12065 -0.2794)
			(end 0.12065 -0.3048)
			(stroke
				(width 0.1)
				(type default)
			)
			(layer "F.Fab")
		)
		(fp_line
			(start 0.67945 -0.3048)
			(end 0.67945 0.3048)
			(stroke
				(width 0.1)
				(type default)
			)
			(layer "F.Fab")
		)
		(fp_line
			(start 0.67945 0.3048)
			(end 0.120396 0.3048)
			(stroke
				(width 0.1)
				(type default)
			)
			(layer "F.Fab")
		)
		(pad "1" smd circle
			(at -0.40005 0)
			(size 0 0)
			(layers "F.Cu" "F.Mask" "F.Paste")
			(net "P3V3_AUX")
		)
		(pad "2" smd circle
			(at 0.40005 0)
			(size 0 0)
			(layers "F.Cu" "F.Mask" "F.Paste")
			(net "GND")
		)
	)
)
